# SCM (Grand Teton) — schematic netlist excerpt (pin names and nets, part order shuffled) for the footprints in the layout excerpt that follows; sources: Cadence DE-HDL packaged netlist, KiCad conversion of 12092022_DA0F0TMDCD0_F0T_Management_Board_D_brd_V3_OCP.brd

R631  Q_RES  16.9K 1% CHIP  pkg 0402LF  page 51 : A = P3V3_LDO ; B = U56_ADJ_1
R593  Q_RES  4.7K 1% EMPTY  pkg 0402LF  page 42 : A = P3V3_AUX ; B = BMC_CPLD_GPIO_7

(kicad_pcb
	(version 20260206)
	(generator "pcbnew")
	(generator_version "10.0")
	(general
		(thickness 1.6)
		(legacy_teardrops no)
	)
	(paper "A4")
	(title_block
		(title "12092022_DA0F0TMDCD0_F0T_Management_Board_D_brd_V3_OCP.brd")
		(comment 1 "Grand Teton / footprints 616-617 of 1440")
	)
	(layers
		(0 "F.Cu" signal "TOP")
		(4 "In1.Cu" signal "GND")
		(6 "In2.Cu" signal "IN1")
		(8 "In3.Cu" signal "GND1")
		(10 "In4.Cu" signal "IN2")
		(12 "In5.Cu" signal "VCC")
		(14 "In6.Cu" signal "VCC1")
		(16 "In7.Cu" signal "IN3")
		(18 "In8.Cu" signal "GND2")
		(20 "In9.Cu" signal "IN4")
		(22 "In10.Cu" signal "GND3")
		(2 "B.Cu" signal "BOTTOM")
		(9 "F.Adhes" user "F.Adhesive")
		(11 "B.Adhes" user "B.Adhesive")
		(13 "F.Paste" user "Package Geometry/Pastemask Top")
		(15 "B.Paste" user "Package Geometry/Pastemask Bottom")
		(5 "F.SilkS" user "Ref Des/Silkscreen Top")
		(7 "B.SilkS" user "Ref Des/Silkscreen Bottom")
		(1 "F.Mask" user "Board Geometry/Soldermask Top")
		(3 "B.Mask" user "Board Geometry/Soldermask Bottom")
		(17 "Dwgs.User" user "User.Drawings")
		(19 "Cmts.User" user "User.Comments")
		(21 "Eco1.User" user "User.Eco1")
		(23 "Eco2.User" user "User.Eco2")
		(25 "Edge.Cuts" user "Board Geometry/Outline")
		(27 "Margin" user)
		(31 "F.CrtYd" user "Package Geometry/Place Bound Top")
		(29 "B.CrtYd" user "Package Geometry/Place Bound Bottom")
		(35 "F.Fab" user "Ref Des/Assembly Top")
		(33 "B.Fab" user "Ref Des/Assembly Bottom")
	)
	(footprint ""
		(layer "F.Cu")
		(at 12.065 -89.789 -90)
		(property "Reference" "R593"
			(at 0 0 270)
			(layer "F.SilkS")
			(hide yes)
			(effects
				(font
					(size 1.27 1.27)
				)
			)
		)
		(property "Value" ""
			(at 0 0 270)
			(layer "F.Fab")
			(effects
				(font
					(size 1.27 1.27)
				)
			)
		)
		(duplicate_pad_numbers_are_jumpers no)
		(fp_line
			(start -0.7874 0.4064)
			(end -0.7874 -0.4064)
			(stroke
				(width 0.1524)
				(type default)
			)
			(layer "F.SilkS")
		)
		(fp_line
			(start 0.7874 0.4064)
			(end -0.7874 0.4064)
			(stroke
				(width 0.1524)
				(type default)
			)
			(layer "F.SilkS")
		)
		(fp_line
			(start -0.7874 -0.4064)
			(end 0.7874 -0.4064)
			(stroke
				(width 0.1524)
				(type default)
			)
			(layer "F.SilkS")
		)
		(fp_line
			(start 0.7874 -0.4064)
			(end 0.7874 0.4064)
			(stroke
				(width 0.1524)
				(type default)
			)
			(layer "F.SilkS")
		)
		(fp_line
			(start -0.67945 0.3048)
			(end -0.67945 -0.305054)
			(stroke
				(width 0.1)
				(type default)
			)
			(layer "F.Fab")
		)
		(fp_line
			(start -0.12065 0.3048)
			(end -0.67945 0.3048)
			(stroke
				(width 0.1)
				(type default)
			)
			(layer "F.Fab")
		)
		(fp_line
			(start 0.120396 0.3048)
			(end 0.120396 0.2794)
			(stroke
				(width 0.1)
				(type default)
			)
			(layer "F.Fab")
		)
		(fp_line
			(start 0.67945 0.3048)
			(end 0.120396 0.3048)
			(stroke
				(width 0.1)
				(type default)
			)
			(layer "F.Fab")
		)
		(fp_line
			(start -0.12065 0.2794)
			(end -0.12065 0.3048)
			(stroke
				(width 0.1)
				(type default)
			)
			(layer "F.Fab")
		)
		(fp_line
			(start 0.120396 0.2794)
			(end -0.12065 0.2794)
			(stroke
				(width 0.1)
				(type default)
			)
			(layer "F.Fab")
		)
		(fp_line
			(start -0.12065 -0.2794)
			(end 0.12065 -0.2794)
			(stroke
				(width 0.1)
				(type default)
			)
			(layer "F.Fab")
		)
		(fp_line
			(start 0.12065 -0.2794)
			(end 0.12065 -0.3048)
			(stroke
				(width 0.1)
				(type default)
			)
			(layer "F.Fab")
		)
		(fp_line
			(start 0.12065 -0.3048)
			(end 0.67945 -0.3048)
			(stroke
				(width 0.1)
				(type default)
			)
			(layer "F.Fab")
		)
		(fp_line
			(start 0.67945 -0.3048)
			(end 0.67945 0.3048)
			(stroke
				(width 0.1)
				(type default)
			)
			(layer "F.Fab")
		)
		(fp_line
			(start -0.67945 -0.305054)
			(end -0.12065 -0.305054)
			(stroke
				(width 0.1)
				(type default)
			)
			(layer "F.Fab")
		)
		(fp_line
			(start -0.12065 -0.305054)
			(end -0.12065 -0.2794)
			(stroke
				(width 0.1)
				(type default)
			)
			(layer "F.Fab")
		)
		(pad "1" smd circle
			(at -0.40005 0 270)
			(size 0 0)
			(layers "F.Cu" "F.Mask" "F.Paste")
			(net "P3V3_AUX")
		)
		(pad "2" smd circle
			(at 0.40005 0 270)
			(size 0 0)
			(layers "F.Cu" "F.Mask" "F.Paste")
			(net "BMC_CPLD_GPIO_7")
		)
	)
	(footprint ""
		(layer "F.Cu")
		(at 75.946 -79.121 180)
		(property "Reference" "R631"
			(at 0 0 180)
			(layer "F.SilkS")
			(hide yes)
			(effects
				(font
					(size 1.27 1.27)
				)
			)
		)
		(property "Value" ""
			(at 0 0 180)
			(layer "F.Fab")
			(effects
				(font
					(size 1.27 1.27)
				)
			)
		)
		(duplicate_pad_numbers_are_jumpers no)
		(fp_line
			(start 0.7874 0.4064)
			(end -0.7874 0.4064)
			(stroke
				(width 0.1524)
				(type default)
			)
			(layer "F.SilkS")
		)
		(fp_line
			(start 0.7874 -0.4064)
			(end 0.7874 0.4064)
			(stroke
				(width 0.1524)
				(type default)
			)
			(layer "F.SilkS")
		)
		(fp_line
			(start -0.7874 0.4064)
			(end -0.7874 -0.4064)
			(stroke
				(width 0.1524)
				(type default)
			)
			(layer "F.SilkS")
		)
		(fp_line
			(start -0.7874 -0.4064)
			(end 0.7874 -0.4064)
			(stroke
				(width 0.1524)
				(type default)
			)
			(layer "F.SilkS")
		)
		(fp_line
			(start 0.67945 0.3048)
			(end 0.120396 0.3048)
			(stroke
				(width 0.1)
				(type default)
			)
			(layer "F.Fab")
		)
		(fp_line
			(start 0.67945 -0.3048)
			(end 0.67945 0.3048)
			(stroke
				(width 0.1)
				(type default)
			)
			(layer "F.Fab")
		)
		(fp_line
			(start 0.12065 -0.2794)
			(end 0.12065 -0.3048)
			(stroke
				(width 0.1)
				(type default)
			)
			(layer "F.Fab")
		)
		(fp_line
			(start 0.12065 -0.3048)
			(end 0.67945 -0.3048)
			(stroke
				(width 0.1)
				(type default)
			)
			(layer "F.Fab")
		)
		(fp_line
			(start 0.120396 0.3048)
			(end 0.120396 0.2794)
			(stroke
				(width 0.1)
				(type default)
			)
			(layer "F.Fab")
		)
		(fp_line
			(start 0.120396 0.2794)
			(end -0.12065 0.2794)
			(stroke
				(width 0.1)
				(type default)
			)
			(layer "F.Fab")
		)
		(fp_line
			(start -0.12065 0.3048)
			(end -0.67945 0.3048)
			(stroke
				(width 0.1)
				(type default)
			)
			(layer "F.Fab")
		)
		(fp_line
			(start -0.12065 0.2794)
			(end -0.12065 0.3048)
			(stroke
				(width 0.1)
				(type default)
			)
			(layer "F.Fab")
		)
		(fp_line
			(start -0.12065 -0.2794)
			(end 0.12065 -0.2794)
			(stroke
				(width 0.1)
				(type default)
			)
			(layer "F.Fab")
		)
		(fp_line
			(start -0.12065 -0.305054)
			(end -0.12065 -0.2794)
			(stroke
				(width 0.1)
				(type default)
			)
			(layer "F.Fab")
		)
		(fp_line
			(start -0.67945 0.3048)
			(end -0.67945 -0.305054)
			(stroke
				(width 0.1)
				(type default)
			)
			(layer "F.Fab")
		)
		(fp_line
			(start -0.67945 -0.305054)
			(end -0.12065 -0.305054)
			(stroke
				(width 0.1)
				(type default)
			)
			(layer "F.Fab")
		)
		(pad "1" smd circle
			(at -0.40005 0 180)
			(size 0 0)
			(layers "F.Cu" "F.Mask" "F.Paste")
			(net "P3V3_LDO")
		)
		(pad "2" smd circle
			(at 0.40005 0 180)
			(size 0 0)
			(layers "F.Cu" "F.Mask" "F.Paste")
			(net "U56_ADJ_1")
		)
	)
)
